# S9S_MB_2U (Grand Teton) — schematic netlist excerpt (pin names and nets, part order shuffled) for the footprints in the layout excerpt that follows; sources: Cadence DE-HDL packaged netlist, KiCad conversion of 03242023_DA0F0TMBIJ0_F0T_Motherboard_J_brd_V01_OCP.brd

J18  SCONN288_ADR50017P087CC  SCONN288_ADR50017-P087CC IO  pkg DDR288S_1-1VXB  page 99
  VIN_BULK0  = P12V_S3_AUX_CPU1_NVDIMM
  RFU0  = TP_CHA_CPU1_DIMM2_FRU_0
  VIN_MGMT  = P3V3_AUX
  HSCL  = I3C_SPD_DDRABCD_CPU1_LVC1_SCL_1
  HSDA  = I3C_SPD_DDRABCD_CPU1_LVC1_SDA
  VSS0  = GND
  DQ0_A  = M_A_CPU1_SA_DQ<0>
  VSS1  = GND
  DQ1_A  = M_A_CPU1_SA_DQ<1>
  VSS2  = GND
  DQS0_A_T  = M_A_CPU1_SA_DQS_DP<0>
  DQS0_A_C  = M_A_CPU1_SA_DQS_DN<0>
  VSS3  = GND
  DQ4_A  = M_A_CPU1_SA_DQ<4>
  VSS4  = GND
  DQ5_A  = M_A_CPU1_SA_DQ<5>
  VSS5  = GND
  DQ8_A  = M_A_CPU1_SA_DQ<8>
  VSS6  = GND
  DQ9_A  = M_A_CPU1_SA_DQ<9>
  VSS7  = GND
  DQS1_A_T  = M_A_CPU1_SA_DQS_DP<1>
  DQS1_A_C  = M_A_CPU1_SA_DQS_DN<1>
  VSS8  = GND
  DQ12_A  = M_A_CPU1_SA_DQ<12>
  VSS9  = GND
  DQ13_A  = M_A_CPU1_SA_DQ<13>
  VSS10  = GND
  DQ16_A  = M_A_CPU1_SA_DQ<16>
  VSS11  = GND
  DQ17_A  = M_A_CPU1_SA_DQ<17>
  VSS12  = GND
  DQS2_A_T  = M_A_CPU1_SA_DQS_DP<2>
  DQS2_A_C  = M_A_CPU1_SA_DQS_DN<2>
  VSS13  = GND
  DQ20_A  = M_A_CPU1_SA_DQ<20>
  VSS14  = GND
  DQ21_A  = M_A_CPU1_SA_DQ<21>
  VSS15  = GND
  DQ24_A  = M_A_CPU1_SA_DQ<24>
  VSS16  = GND
  DQ25_A  = M_A_CPU1_SA_DQ<25>
  VSS17  = GND
  DQS3_A_T  = M_A_CPU1_SA_DQS_DP<3>
  DQS3_A_C  = M_A_CPU1_SA_DQS_DN<3>
  VSS18  = GND
  DQ28_A  = M_A_CPU1_SA_DQ<28>
  VSS19  = GND
  DQ29_A  = M_A_CPU1_SA_DQ<29>
  VSS20  = GND
  CB0_A  = M_A_CPU1_SA_CB<0>
  VSS21  = GND
  CB1_A  = M_A_CPU1_SA_CB<1>
  VSS22  = GND
  DQS4_A_T  = M_A_CPU1_SA_DQS_DP<4>
  DQS4_A_C  = M_A_CPU1_SA_DQS_DN<4>
  VSS23  = GND
  CB4_A  = M_A_CPU1_SA_CB<4>
  VSS24  = GND
  CB5_A  = M_A_CPU1_SA_CB<5>
  VSS25  = GND
  ALERT_N  = M_A_CPU1_ALERT_N
  VSS26  = GND
  CS0_A_N  = M_A_CPU1_SA_CS_N<2>
  VSS27  = GND
  CA0_A  = M_A_CPU1_SA_CA<0>
  VSS28  = GND
  CA2_A  = M_A_CPU1_SA_CA<2>
  VSS29  = GND
  CA4_A  = M_A_CPU1_SA_CA<4>
  VSS30  = GND
  CA6_A  = M_A_CPU1_SA_CA<6>
  VSS31  = GND
  PAR_A  = M_A_CPU1_SA_PAR
  VSS32  = GND
  CA0_B  = M_A_CPU1_SB_CA<0>
  VSS33  = GND
  CA2_B  = M_A_CPU1_SB_CA<2>
  VSS34  = GND
  CA4_B  = M_A_CPU1_SB_CA<4>
  VSS35  = GND
  CA6_B  = M_A_CPU1_SB_CA<6>
  VSS36  = GND
  CS0_B_N  = M_A_CPU1_SB_CS_N<2>
  VSS37  = GND
  \lbd||rsp_a_n\  = M_A_CPU1_SA_RSP<1>
  \lbs||rsp_b_n\  = M_A_CPU1_SB_RSP<1>
  VSS38  = GND
  CB4_B  = M_A_CPU1_SB_CB<4>
  VSS39  = GND
  CB5_B  = M_A_CPU1_SB_CB<5>
  VSS40  = GND
  \dqs9_b_t||tdqs9_b_t||dbi4_b_n\  = M_A_CPU1_SB_DQS_DP<9>
  \dqs9_b_c||tdqs9_b_c\  = M_A_CPU1_SB_DQS_DN<9>
  VSS41  = GND
  CB0_B  = M_A_CPU1_SB_CB<0>
  VSS42  = GND
  CB1_B  = M_A_CPU1_SB_CB<1>
  VSS43  = GND
  DQ0_B  = M_A_CPU1_SB_DQ<0>
  VSS44  = GND
  DQ1_B  = M_A_CPU1_SB_DQ<1>
  VSS45  = GND
  DQS0_B_T  = M_A_CPU1_SB_DQS_DP<0>
  DQS0_B_C  = M_A_CPU1_SB_DQS_DN<0>
  VSS46  = GND
  DQ4_B  = M_A_CPU1_SB_DQ<4>
  VSS47  = GND
  DQ5_B  = M_A_CPU1_SB_DQ<5>
  VSS48  = GND
  DQ8_B  = M_A_CPU1_SB_DQ<8>
  VSS49  = GND
  DQ9_B  = M_A_CPU1_SB_DQ<9>
  VSS50  = GND
  DQS1_B_T  = M_A_CPU1_SB_DQS_DP<1>
  DQS1_B_C  = M_A_CPU1_SB_DQS_DN<1>
  VSS51  = GND
  DQ12_B  = M_A_CPU1_SB_DQ<12>
  VSS52  = GND
  DQ13_B  = M_A_CPU1_SB_DQ<13>
  VSS53  = GND
  DQ16_B  = M_A_CPU1_SB_DQ<16>
  VSS54  = GND
  DQ17_B  = M_A_CPU1_SB_DQ<17>
  VSS55  = GND
  DQS2_B_T  = M_A_CPU1_SB_DQS_DP<2>
  DQS2_B_C  = M_A_CPU1_SB_DQS_DN<2>
  VSS56  = GND
  DQ20_B  = M_A_CPU1_SB_DQ<20>
  VSS57  = GND
  DQ21_B  = M_A_CPU1_SB_DQ<21>
  VSS58  = GND
  DQ24_B  = M_A_CPU1_SB_DQ<24>
  VSS59  = GND
  DQ25_B  = M_A_CPU1_SB_DQ<25>
  VSS60  = GND
  DQS3_B_T  = M_A_CPU1_SB_DQS_DP<3>
  DQS3_B_C  = M_A_CPU1_SB_DQS_DN<3>
  VSS61  = GND
  DQ28_B  = M_A_CPU1_SB_DQ<28>
  VSS62  = GND
  DQ29_B  = M_A_CPU1_SB_DQ<29>
  VSS63  = GND
  RFU1  = TP_CHA_CPU1_DIMM2_FRU_1
  VIN_BULK1  = P12V_S3_AUX_CPU1_NVDIMM
  VIN_BULK2  = P12V_S3_AUX_CPU1_NVDIMM
  \pwr_good||fail_n\  = PWRGD_CHA_CPU1_DIMM2
  HSA  = PD_CHA_CPU1_DIMM2_SAA
  RFU2  = TP_CHA_CPU1_DIMM2_FRU_2
  RFU3  = TP_CHA_CPU1_DIMM2_FRU_3
  VSS64  = GND
  DQ2_A  = M_A_CPU1_SA_DQ<2>
  VSS65  = GND
  DQ3_A  = M_A_CPU1_SA_DQ<3>
  VSS66  = GND
  \dqs5_a_c||tdqs5_a_c||dqs5_a_t||tdqs5_a_t\  = M_A_CPU1_SA_DQS_DN<5>
  \dqs5_a_t||tdqs5_a_t\  = M_A_CPU1_SA_DQS_DP<5>
  VSS67  = GND
  DQ6_A  = M_A_CPU1_SA_DQ<6>
  VSS68  = GND
  DQ7_A  = M_A_CPU1_SA_DQ<7>
  VSS69  = GND
  DQ10_A  = M_A_CPU1_SA_DQ<10>
  VSS70  = GND
  DQ11_A  = M_A_CPU1_SA_DQ<11>
  VSS71  = GND
  \dqs6_a_c||tdqs6_a_c||dqs6_a_t||tdqs6_a_t\  = M_A_CPU1_SA_DQS_DN<6>
  \dqs6_a_t||tdqs6_a_t\  = M_A_CPU1_SA_DQS_DP<6>
  VSS72  = GND
  DQ14_A  = M_A_CPU1_SA_DQ<14>
  VSS73  = GND
  DQ15_A  = M_A_CPU1_SA_DQ<15>
  VSS74  = GND
  DQ18_A  = M_A_CPU1_SA_DQ<18>
  VSS75  = GND
  DQ19_A  = M_A_CPU1_SA_DQ<19>
  VSS76  = GND
  \dqs7_a_c||tdqs7_a_c\  = M_A_CPU1_SA_DQS_DN<7>
  \dqs7_a_t||tdqs7_a_t\  = M_A_CPU1_SA_DQS_DP<7>
  VSS77  = GND
  DQ22_A  = M_A_CPU1_SA_DQ<22>
  VSS78  = GND
  DQ23_A  = M_A_CPU1_SA_DQ<23>
  VSS79  = GND
  DQ26_A  = M_A_CPU1_SA_DQ<26>
  VSS80  = GND
  DQ27_A  = M_A_CPU1_SA_DQ<27>
  VSS81  = GND
  \dqs8_a_c||tdqs8_a_c\  = M_A_CPU1_SA_DQS_DN<8>
  \dqs8_a_t||tdqs8_a_t\  = M_A_CPU1_SA_DQS_DP<8>
  VSS82  = GND
  DQ30_A  = M_A_CPU1_SA_DQ<30>
  VSS83  = GND
  DQ31_A  = M_A_CPU1_SA_DQ<31>
  VSS84  = GND
  CB2_A  = M_A_CPU1_SA_CB<2>
  VSS85  = GND
  CB3_A  = M_A_CPU1_SA_CB<3>
  VSS86  = GND
  \dqs9_a_c||tdqs9_a_c\  = M_A_CPU1_SA_DQS_DN<9>
  \dqs9_a_t||tdqs9_a_t\  = M_A_CPU1_SA_DQS_DP<9>
  VSS87  = GND
  CB6_A  = M_A_CPU1_SA_CB<6>
  VSS88  = GND
  CB7_A  = M_A_CPU1_SA_CB<7>
  VSS89  = GND
  RESET_N  = RST_M_AB_CPU1_FPGA_N
  VSS90  = GND
  CS1_A_N  = M_A_CPU1_SA_CS_N<3>
  VSS91  = GND
  CA1_A  = M_A_CPU1_SA_CA<1>
  VSS92  = GND
  CA3_A  = M_A_CPU1_SA_CA<3>
  VSS93  = GND
  CA5_A  = M_A_CPU1_SA_CA<5>
  VSS94  = GND
  CK_T  = M_A_CPU1_CLK_DP<1>
  CK_C  = M_A_CPU1_CLK_DN<1>
  VSS95  = GND
  RFU4  = TP_CHA_CPU1_DIMM2_FRU_4
  CA1_B  = M_A_CPU1_SB_CA<1>
  VSS96  = GND
  CA3_B  = M_A_CPU1_SB_CA<3>
  VSS97  = GND
  CA5_B  = M_A_CPU1_SB_CA<5>
  VSS98  = GND
  PAR_B  = M_A_CPU1_SB_PAR
  VSS99  = GND
  CS1_B_N  = M_A_CPU1_SB_CS_N<3>
  VSS100  = GND
  RFU5  = TP_CHA_CPU1_DIMM2_FRU_5
  RFU6  = TP_CHA_CPU1_DIMM2_FRU_6
  VSS101  = GND
  CB6_B  = M_A_CPU1_SB_CB<6>
  VSS102  = GND
  CB7_B  = M_A_CPU1_SB_CB<7>
  VSS103  = GND
  DQS4_B_C  = M_A_CPU1_SB_DQS_DN<4>
  DQS4_B_T  = M_A_CPU1_SB_DQS_DP<4>
  VSS104  = GND
  CB2_B  = M_A_CPU1_SB_CB<2>
  VSS105  = GND
  CB3_B  = M_A_CPU1_SB_CB<3>
  VSS106  = GND
  DQ2_B  = M_A_CPU1_SB_DQ<2>
  VSS107  = GND
  DQ3_B  = M_A_CPU1_SB_DQ<3>
  VSS108  = GND
  \dqs5_b_c||tdqs5_b_c\  = M_A_CPU1_SB_DQS_DN<5>
  \dqs5_b_t||tdqs5_b_t\  = M_A_CPU1_SB_DQS_DP<5>
  VSS109  = GND
  DQ6_B  = M_A_CPU1_SB_DQ<6>
  VSS110  = GND
  DQ7_B  = M_A_CPU1_SB_DQ<7>
  VSS111  = GND
  DQ10_B  = M_A_CPU1_SB_DQ<10>
  VSS112  = GND
  DQ11_B  = M_A_CPU1_SB_DQ<11>
  VSS113  = GND
  \dqs6_b_c||tdqs6_b_c\  = M_A_CPU1_SB_DQS_DN<6>
  \dqs6_b_t||tdqs6_b_t\  = M_A_CPU1_SB_DQS_DP<6>
  VSS114  = GND
  DQ14_B  = M_A_CPU1_SB_DQ<14>
  VSS115  = GND
  DQ15_B  = M_A_CPU1_SB_DQ<15>
  VSS116  = GND
  DQ18_B  = M_A_CPU1_SB_DQ<18>
  VSS117  = GND
  DQ19_B  = M_A_CPU1_SB_DQ<19>
  VSS118  = GND
  \dqs7_b_c||tdqs7_b_c\  = M_A_CPU1_SB_DQS_DN<7>
  \dqs7_b_t||tdqs7_b_t\  = M_A_CPU1_SB_DQS_DP<7>
  VSS119  = GND
  DQ22_B  = M_A_CPU1_SB_DQ<22>
  VSS120  = GND
  DQ23_B  = M_A_CPU1_SB_DQ<23>
  VSS121  = GND
  DQ26_B  = M_A_CPU1_SB_DQ<26>
  VSS122  = GND
  DQ27_B  = M_A_CPU1_SB_DQ<27>
  VSS123  = GND
  \dqs8_b_c||tdqs8_b_c\  = M_A_CPU1_SB_DQS_DN<8>
  \dqs8_b_t||tdqs8_b_t\  = M_A_CPU1_SB_DQS_DP<8>
  VSS124  = GND
  DQ30_B  = M_A_CPU1_SB_DQ<30>
  VSS125  = GND
  DQ31_B  = M_A_CPU1_SB_DQ<31>
  VSS126  = GND
  G1  = GND
  G2  = GND
  G3  = GND

(kicad_pcb
	(version 20260206)
	(generator "pcbnew")
	(generator_version "10.0")
	(general
		(thickness 1.6)
		(legacy_teardrops no)
	)
	(paper "A4")
	(title_block
		(title "03242023_DA0F0TMBIJ0_F0T_Motherboard_J_brd_V01_OCP.brd")
		(comment 1 "Grand Teton / footprint 3819 of 6105 (J18), pads 275-291 of 291")
	)
	(layers
		(0 "F.Cu" signal "TOP")
		(4 "In1.Cu" signal "GND")
		(6 "In2.Cu" signal "IN1")
		(8 "In3.Cu" signal "GND1")
		(10 "In4.Cu" signal "IN2")
		(12 "In5.Cu" signal "GND2")
		(14 "In6.Cu" signal "IN3")
		(16 "In7.Cu" signal "GND3")
		(18 "In8.Cu" signal "VCC")
		(20 "In9.Cu" signal "VCC1")
		(22 "In10.Cu" signal "GND4")
		(24 "In11.Cu" signal "IN4")
		(26 "In12.Cu" signal "GND5")
		(28 "In13.Cu" signal "IN5")
		(30 "In14.Cu" signal "GND6")
		(32 "In15.Cu" signal "IN6")
		(34 "In16.Cu" signal "GND7")
		(2 "B.Cu" signal "BOTTOM")
		(9 "F.Adhes" user "F.Adhesive")
		(11 "B.Adhes" user "B.Adhesive")
		(13 "F.Paste" user "Package Geometry/Pastemask Top")
		(15 "B.Paste" user "Package Geometry/Pastemask Bottom")
		(5 "F.SilkS" user "Ref Des/Silkscreen Top")
		(7 "B.SilkS" user "Ref Des/Silkscreen Bottom")
		(1 "F.Mask" user "Board Geometry/Soldermask Top")
		(3 "B.Mask" user "Board Geometry/Soldermask Bottom")
		(17 "Dwgs.User" user "User.Drawings")
		(19 "Cmts.User" user "User.Comments")
		(21 "Eco1.User" user "User.Eco1")
		(23 "Eco2.User" user "User.Eco2")
		(25 "Edge.Cuts" user "Board Geometry/Outline")
		(27 "Margin" user)
		(31 "F.CrtYd" user "Package Geometry/Place Bound Top")
		(29 "B.CrtYd" user "Package Geometry/Place Bound Bottom")
		(35 "F.Fab" user "Ref Des/Assembly Top")
		(33 "B.Fab" user "Ref Des/Assembly Bottom")
	)
	(footprint ""
		(layer "F.Cu")
		(at 62.99708 -258.091686)
		(property "Reference" "J18"
			(at -1.547622 -81.836514 0)
			(unlocked yes)
			(layer "F.SilkS")
			(effects
				(font
					(size 0.7874 0.5842)
					(thickness 0.1524)
				)
				(justify left)
			)
		)
		(property "Value" ""
			(at 0 0 0)
			(layer "F.Fab")
			(effects
				(font
					(size 1.27 1.27)
				)
			)
		)
		(duplicate_pad_numbers_are_jumpers no)
		(pad "275" smd rect
			(at 2.050034 52.274978 270)
			(size 0.519938 1.4986)
			(layers "F.Cu" "F.Mask" "F.Paste")
			(net "GND")
		)
		(pad "276" smd rect
			(at 2.050034 53.125116 270)
			(size 0.519938 1.4986)
			(layers "F.Cu" "F.Mask" "F.Paste")
			(net "M_A_CPU1_SB_DQ<23>")
		)
		(pad "277" smd rect
			(at 2.050034 53.975 270)
			(size 0.519938 1.4986)
			(layers "F.Cu" "F.Mask" "F.Paste")
			(net "GND")
		)
		(pad "278" smd rect
			(at 2.050034 54.824884 270)
			(size 0.519938 1.4986)
			(layers "F.Cu" "F.Mask" "F.Paste")
			(net "M_A_CPU1_SB_DQ<26>")
		)
		(pad "279" smd rect
			(at 2.050034 55.675022 270)
			(size 0.519938 1.4986)
			(layers "F.Cu" "F.Mask" "F.Paste")
			(net "GND")
		)
		(pad "280" smd rect
			(at 2.050034 56.524906 270)
			(size 0.519938 1.4986)
			(layers "F.Cu" "F.Mask" "F.Paste")
			(net "M_A_CPU1_SB_DQ<27>")
		)
		(pad "281" smd rect
			(at 2.050034 57.375044 270)
			(size 0.519938 1.4986)
			(layers "F.Cu" "F.Mask" "F.Paste")
			(net "GND")
		)
		(pad "282" smd rect
			(at 2.050034 58.224928 270)
			(size 0.519938 1.4986)
			(layers "F.Cu" "F.Mask" "F.Paste")
			(net "M_A_CPU1_SB_DQS_DN<8>")
		)
		(pad "283" smd rect
			(at 2.050034 59.075066 270)
			(size 0.519938 1.4986)
			(layers "F.Cu" "F.Mask" "F.Paste")
			(net "M_A_CPU1_SB_DQS_DP<8>")
		)
		(pad "284" smd rect
			(at 2.050034 59.92495 270)
			(size 0.519938 1.4986)
			(layers "F.Cu" "F.Mask" "F.Paste")
			(net "GND")
		)
		(pad "285" smd rect
			(at 2.050034 60.775088 270)
			(size 0.519938 1.4986)
			(layers "F.Cu" "F.Mask" "F.Paste")
			(net "M_A_CPU1_SB_DQ<30>")
		)
		(pad "286" smd rect
			(at 2.050034 61.624972 270)
			(size 0.519938 1.4986)
			(layers "F.Cu" "F.Mask" "F.Paste")
			(net "GND")
		)
		(pad "287" smd rect
			(at 2.050034 62.47511 270)
			(size 0.519938 1.4986)
			(layers "F.Cu" "F.Mask" "F.Paste")
			(net "M_A_CPU1_SB_DQ<31>")
		)
		(pad "288" smd rect
			(at 2.050034 63.324994 270)
			(size 0.519938 1.4986)
			(layers "F.Cu" "F.Mask" "F.Paste")
			(net "GND")
		)
		(pad "G1" thru_hole oval
			(at 0 -68.97497)
			(size 2.8194 1.5748)
			(drill oval 2.4384 1.1938)
			(layers "*.Cu" "*.Mask")
			(remove_unused_layers no)
			(net "GND")
			(clearance 0.127)
			(thermal_gap 0.127)
		)
		(pad "G2" thru_hole oval
			(at 0 3.875024)
			(size 2.8194 1.5748)
			(drill oval 2.4384 1.1938)
			(layers "*.Cu" "*.Mask")
			(remove_unused_layers no)
			(net "GND")
			(clearance 0.127)
			(thermal_gap 0.127)
		)
		(pad "G3" thru_hole oval
			(at 0 68.97497)
			(size 2.8194 1.5748)
			(drill oval 2.4384 1.1938)
			(layers "*.Cu" "*.Mask")
			(remove_unused_layers no)
			(net "GND")
			(clearance 0.127)
			(thermal_gap 0.127)
		)
	)
)
